G04 ================== begin FILE IDENTIFICATION RECORD ==================*
G04 Layout Name:  t6m_pdb_d_0928_1400_274.brd*
G04 Film Name:    pmt*
G04 File Format:  Gerber RS274X*
G04 File Origin:  Cadence Allegro 16.3-S048*
G04 Origin Date:  Tue Nov 26 11:01:52 2013*
G04 *
G04 Layer:  VIA CLASS/PASTEMASK_TOP*
G04 Layer:  PIN/PASTEMASK_TOP*
G04 Layer:  PACKAGE GEOMETRY/PASTEMASK_TOP*
G04 Layer:  MANUFACTURING/PHOTOPLOT_OUTLINE*
G04 Layer:  DRAWING FORMAT/TITLE_BLOCK*
G04 Layer:  DRAWING FORMAT/TITLE_DATA_PMT*
G04 *
G04 Offset:    (0.00 0.00)*
G04 Mirror:    No*
G04 Mode:      Positive*
G04 Rotation:  0*
G04 FullContactRelief:  No*
G04 UndefLineWidth:     6.00*
G04 ================== end FILE IDENTIFICATION RECORD ====================*
%FSLAX25Y25*MOIN*%
%IR0*IPPOS*OFA0.00000B0.00000*MIA0B0*SFA1.00000B1.00000*%
%ADD20C,.03*%
%ADD15C,.06*%
%ADD12C,.052*%
%ADD24C,.064*%
%ADD10C,.055*%
%ADD21C,.039*%
%ADD13C,.093*%
%ADD16R,.06X.06*%
%ADD18C,.077*%
%ADD17R,.052X.052*%
%ADD25R,.064X.064*%
%ADD11R,.055X.055*%
%ADD19R,.077X.077*%
%ADD14R,.02X.018*%
%ADD22R,.018X.02*%
%ADD26R,.028X.032*%
%ADD23R,.022X.068*%
%ADD27C,.006*%
G75*
%LPD*%
G75*
G54D10*
X17735Y24953D03*
X27735D03*
X22735Y34953D03*
Y216976D03*
X27735Y206976D03*
X17735Y233811D03*
X27735D03*
X22735Y243811D03*
X27735Y415834D03*
X22735Y425834D03*
Y1957291D03*
X27735Y1947291D03*
X22735Y2061661D03*
X27735Y2051661D03*
X37735Y24953D03*
X47735D03*
X32735Y34953D03*
X42735D03*
Y216976D03*
X32735D03*
X47735Y206976D03*
X37735D03*
Y233811D03*
X47735D03*
X32735Y243811D03*
X42735D03*
X47735Y415834D03*
X37735D03*
X42735Y425834D03*
X32735D03*
X42735Y1957291D03*
X32735D03*
X47735Y1947291D03*
X37735D03*
X42735Y2061661D03*
X32735D03*
X47735Y2051661D03*
X37735D03*
X52735Y216976D03*
Y425834D03*
Y1957291D03*
Y2061661D03*
X189762Y73105D03*
X190289Y152050D03*
X190357Y247568D03*
X190817Y331786D03*
X189761Y421732D03*
X190553Y506517D03*
X192888Y598130D03*
X190816Y681645D03*
X191846Y774526D03*
X191606Y856244D03*
X196311Y947202D03*
X195516Y1032544D03*
X191250Y1122856D03*
X191342Y1206233D03*
X191846Y1299104D03*
X190552Y1380966D03*
X189463Y1474162D03*
X191079Y1557277D03*
X192143Y1648177D03*
X191607Y1731351D03*
X191530Y1823227D03*
X190289Y1900420D03*
X192125Y1998730D03*
X191530Y2043388D03*
G54D11*
X17735Y206976D03*
Y415834D03*
Y1947291D03*
Y2051661D03*
X52735Y34953D03*
Y243811D03*
X203542Y73105D03*
X204069Y152050D03*
X204137Y247568D03*
X204597Y331786D03*
X203541Y421732D03*
X204333Y506517D03*
X206668Y598130D03*
X204596Y681645D03*
X205626Y774526D03*
X205386Y856244D03*
X210091Y947202D03*
X209296Y1032544D03*
X205030Y1122856D03*
X205122Y1206233D03*
X205626Y1299104D03*
X204332Y1380966D03*
X203243Y1474162D03*
X204859Y1557277D03*
X205923Y1648177D03*
X205387Y1731351D03*
X205310Y1823227D03*
X204069Y1900420D03*
X205905Y1998730D03*
X205310Y2043388D03*
G54D20*
X65354Y101180D03*
X55511Y105117D03*
X51574Y114960D03*
X55511Y124803D03*
X65354Y128740D03*
Y451180D03*
X55511Y455117D03*
X51574Y464960D03*
X55511Y474803D03*
X65354Y478740D03*
Y801180D03*
X55511Y805117D03*
X51574Y814960D03*
X55511Y824803D03*
X65354Y828740D03*
Y1151180D03*
X55511Y1155117D03*
X51574Y1164960D03*
X55511Y1174803D03*
X65354Y1178740D03*
Y1501180D03*
X55511Y1505117D03*
X51574Y1514960D03*
X55511Y1524803D03*
X65354Y1528740D03*
Y1851180D03*
X55511Y1855117D03*
X51574Y1864960D03*
X55511Y1874803D03*
X65354Y1878740D03*
X75197Y105117D03*
Y124803D03*
X79134Y114960D03*
Y464960D03*
X75197Y455117D03*
Y474803D03*
Y805117D03*
Y824803D03*
X79134Y814960D03*
Y1164960D03*
X75197Y1155117D03*
Y1174803D03*
Y1505117D03*
Y1524803D03*
X79134Y1514960D03*
Y1864960D03*
X75197Y1855117D03*
Y1874803D03*
X307086Y113385D03*
X297243Y117322D03*
X293306Y127165D03*
X297243Y137008D03*
X307086Y140945D03*
Y463385D03*
X297243Y467322D03*
X293306Y477165D03*
X297243Y487008D03*
X307086Y490945D03*
Y813385D03*
X297243Y817322D03*
X293306Y827165D03*
X297243Y837008D03*
X307086Y840945D03*
Y1329724D03*
X297243Y1333661D03*
X293306Y1343504D03*
X297243Y1353347D03*
X307086Y1357284D03*
Y1679724D03*
X297243Y1683661D03*
X293306Y1693504D03*
X297243Y1703347D03*
X307086Y1707284D03*
X307087Y2029723D03*
X297244Y2033660D03*
X293307Y2043503D03*
X297244Y2053346D03*
X307087Y2057283D03*
X320866Y127165D03*
X316929Y117322D03*
Y137008D03*
Y467322D03*
Y487008D03*
X320866Y477165D03*
Y827165D03*
X316929Y817322D03*
Y837008D03*
Y1333661D03*
Y1353347D03*
X320866Y1343504D03*
Y1693504D03*
X316929Y1683661D03*
Y1703347D03*
X316930Y2033660D03*
Y2053346D03*
X320867Y2043503D03*
G54D21*
X56337Y878761D03*
X388591Y62106D03*
X385616Y1991570D03*
G54D12*
X18995Y508701D03*
X23995Y518701D03*
X21495Y559882D03*
X11692D03*
X21495Y1571811D03*
X11692D03*
X23995Y1622992D03*
X28995Y508701D03*
X38995D03*
X48995D03*
X33995Y518701D03*
X43995D03*
X51495Y559882D03*
Y1571811D03*
X43995Y1622992D03*
X33995D03*
X48995Y1612992D03*
X38995D03*
X28995D03*
X61298Y559882D03*
Y1571811D03*
X53995Y1622992D03*
G54D22*
X54413Y1253378D03*
X51263D03*
X54210Y1263103D03*
X51060D03*
X54277Y1257633D03*
X51127D03*
X54582Y1279783D03*
X51432D03*
X54548Y1267290D03*
X51398D03*
X54446Y1284038D03*
X51296D03*
X54582Y1275630D03*
X51432D03*
X54481Y1271544D03*
X51331D03*
X61280Y1559138D03*
X58130D03*
X105845Y20080D03*
X108995D03*
X100778Y28320D03*
X103928D03*
X100693Y24203D03*
X103843D03*
X105845Y15847D03*
X108995D03*
X108090Y46285D03*
X104940D03*
X104932Y41803D03*
X108082D03*
X100778Y32853D03*
X103928D03*
X100778Y37438D03*
X103928D03*
X104137Y78186D03*
X107287D03*
X102727Y58250D03*
X105877D03*
X100518Y391220D03*
X103668D03*
X100518Y376580D03*
X103668D03*
X100518Y386235D03*
X103668D03*
X100518Y381386D03*
X103668D03*
X100518Y371909D03*
X103668D03*
X100518Y396024D03*
X103668D03*
X100794Y400352D03*
X103944D03*
X104518Y426104D03*
X107668D03*
X101056Y720745D03*
X104206D03*
X101056Y730398D03*
X104206D03*
X101056Y725457D03*
X104206D03*
X101056Y715937D03*
X104206D03*
X104346Y745139D03*
X101196D03*
X101056Y735248D03*
X104206D03*
X101056Y739962D03*
X104206D03*
X101520Y749481D03*
X104670D03*
X104442Y774100D03*
X107592D03*
X101189Y1067515D03*
X104339D03*
X101189Y1092036D03*
X104339D03*
X101189Y1072226D03*
X104339D03*
X101189Y1081791D03*
X104339D03*
X101189Y1076901D03*
X104339D03*
X101189Y1087095D03*
X104339D03*
X104432Y1096403D03*
X101282D03*
X105880Y1102535D03*
X109030D03*
X105684Y1122166D03*
X108834D03*
X100227Y1419492D03*
X103377D03*
X100227Y1429195D03*
X103377D03*
X100227Y1424340D03*
X103377D03*
X103443Y1447919D03*
X100293D03*
X100227Y1443743D03*
X103377D03*
X100227Y1434041D03*
X103377D03*
X100227Y1438980D03*
X103377D03*
X100019Y1453131D03*
X103169D03*
X105390Y1470205D03*
X108540D03*
X101677Y1760827D03*
X104827D03*
X101677Y1770527D03*
X104827D03*
X101677Y1765722D03*
X104827D03*
X104930Y1789947D03*
X101780D03*
X101677Y1785571D03*
X104827D03*
X101677Y1775514D03*
X104827D03*
X101677Y1780542D03*
X104827D03*
X105669Y1818228D03*
X108819D03*
X103671Y1798224D03*
X106821D03*
X159676Y56744D03*
X156526D03*
X158463Y68130D03*
X155313D03*
X155202Y72497D03*
X158352D03*
X158559Y88108D03*
X155409D03*
X158490Y407575D03*
X155340D03*
X158498Y436119D03*
X155348D03*
X158950Y756757D03*
X155800D03*
X158665Y764231D03*
X155515D03*
X155113Y776673D03*
X158263D03*
X158519Y784141D03*
X155369D03*
X159278Y1106853D03*
X156128D03*
X158497Y1132178D03*
X155347D03*
X160252Y1457084D03*
X157102D03*
X158976Y1480269D03*
X155826D03*
X159505Y1462651D03*
X156355D03*
X155648Y1473020D03*
X158798D03*
X158840Y1807740D03*
X155690D03*
X158563Y1815631D03*
X155413D03*
X158806Y1828225D03*
X155656D03*
X155409Y1820360D03*
X158559D03*
X184373Y937979D03*
X181223D03*
X184284Y943579D03*
X181134D03*
X184196Y962671D03*
X181046D03*
X184285Y957071D03*
X181135D03*
X184539Y973554D03*
X181389D03*
X184397Y990958D03*
X181247D03*
X184632Y979154D03*
X181482D03*
X184353Y996558D03*
X181203D03*
X184118Y1015313D03*
X180968D03*
X184115Y1009713D03*
X180965D03*
X182329Y1025022D03*
X179179D03*
X182327Y1030622D03*
X179177D03*
X264685Y128228D03*
X261535D03*
X264929Y115559D03*
X261779D03*
X264175Y823604D03*
X261025D03*
X264335Y812170D03*
X261185D03*
X272111Y463099D03*
X268961D03*
X272038Y473677D03*
X268888D03*
X288712Y1864565D03*
X285562D03*
X288794Y1858668D03*
X285644D03*
X308906Y1524401D03*
X305756D03*
X308636Y1513883D03*
X305486D03*
X320208Y1162266D03*
X317058D03*
X320264Y1172804D03*
X317114D03*
G54D13*
X5491Y528544D03*
Y1603149D03*
X67499Y528544D03*
Y1603149D03*
G54D23*
X71866Y1315303D03*
X66866D03*
X61866D03*
X56866D03*
Y1336103D03*
X61866D03*
X66866D03*
X71866D03*
G54D14*
X11677Y572812D03*
Y575962D03*
X16484Y1555159D03*
Y1558309D03*
X11085Y1555291D03*
Y1558441D03*
X58750Y577016D03*
Y573866D03*
X63820Y577082D03*
Y573932D03*
X58752Y1302746D03*
Y1299596D03*
X71909Y1302580D03*
Y1299430D03*
X50331Y1302680D03*
Y1299530D03*
X54543Y1302681D03*
Y1299531D03*
X63061Y1302746D03*
Y1299596D03*
X67568Y1302581D03*
Y1299431D03*
X52958Y1336081D03*
Y1339231D03*
X107268Y78205D03*
X107263Y75055D03*
Y78205D03*
X107268Y81355D03*
X107668Y429254D03*
Y426104D03*
Y422954D03*
Y426104D03*
X107615Y777299D03*
Y774149D03*
X107617Y771001D03*
Y774151D03*
X108819Y1119015D03*
X108816Y1125313D03*
Y1122163D03*
X108819Y1122165D03*
X108573Y1473357D03*
Y1470207D03*
X108574Y1467057D03*
Y1470207D03*
X108819Y1818228D03*
Y1815078D03*
Y1818228D03*
Y1821378D03*
X155370Y91281D03*
Y88131D03*
X155366Y85017D03*
Y88167D03*
X156321Y418198D03*
Y415048D03*
X161256Y418195D03*
Y415045D03*
X155351Y439268D03*
Y436118D03*
X155348Y432969D03*
Y436119D03*
X155356Y780982D03*
X155362Y787280D03*
Y784130D03*
X155356Y784132D03*
X156117Y1116127D03*
Y1112977D03*
X160870Y1116135D03*
Y1112985D03*
X155264Y1135344D03*
Y1132194D03*
X155263Y1129045D03*
Y1132195D03*
X155834Y1480274D03*
X155816Y1477124D03*
Y1480274D03*
X155834Y1483424D03*
X155570Y1831380D03*
Y1828230D03*
X155561Y1825087D03*
Y1828237D03*
X283086Y166264D03*
Y169414D03*
X287420Y166264D03*
Y169414D03*
X276617Y238439D03*
Y235289D03*
X281193Y238439D03*
Y235289D03*
X281074Y341517D03*
Y344667D03*
X289895Y341517D03*
Y344667D03*
X285513Y341517D03*
Y344667D03*
X291002Y414015D03*
Y410865D03*
X286665Y414015D03*
Y410865D03*
X278405Y515919D03*
Y519069D03*
X273938Y515919D03*
Y519069D03*
X282776Y515919D03*
Y519069D03*
X269516Y515919D03*
Y519069D03*
X290984Y585487D03*
Y588637D03*
X283340Y691124D03*
Y694274D03*
X278955Y691124D03*
Y694274D03*
X274514Y691124D03*
Y694274D03*
X270109Y691124D03*
Y694274D03*
X278184Y763711D03*
Y760561D03*
X282737Y763711D03*
Y760561D03*
X285788Y866243D03*
Y869393D03*
X281305Y866243D03*
Y869393D03*
X276686Y866243D03*
Y869393D03*
X272181Y866243D03*
Y869393D03*
X281194Y937436D03*
Y934286D03*
X285874Y937436D03*
Y934286D03*
X290107Y1034882D03*
Y1038032D03*
X285666Y1034882D03*
Y1038032D03*
X281124Y1034882D03*
Y1038032D03*
X288188Y1112426D03*
Y1109276D03*
X284194Y1210314D03*
Y1213464D03*
X289082Y1210314D03*
Y1213464D03*
X279559Y1210314D03*
Y1213464D03*
X289210Y1287097D03*
Y1283947D03*
X284240Y1393342D03*
Y1396492D03*
X279518Y1393341D03*
Y1396491D03*
X275052Y1393341D03*
Y1396491D03*
X270579Y1393341D03*
Y1396491D03*
X275521Y1457487D03*
X279990D03*
X275521Y1460637D03*
X279990D03*
X289675Y1562451D03*
Y1565601D03*
X285054Y1562451D03*
Y1565601D03*
X289421Y1637318D03*
Y1634168D03*
X289499Y1741915D03*
Y1745065D03*
X284583Y1741915D03*
Y1745065D03*
X274704Y1741915D03*
Y1745065D03*
X279703Y1741915D03*
Y1745065D03*
X286623Y1811546D03*
Y1808396D03*
X291550Y1811546D03*
Y1808396D03*
X287121Y1916895D03*
Y1920045D03*
X282717Y1916895D03*
Y1920045D03*
X278262Y1916895D03*
Y1920045D03*
X273817Y1916895D03*
Y1920045D03*
X304151Y60393D03*
Y57243D03*
X308651Y60393D03*
Y57243D03*
X313089Y60393D03*
Y57243D03*
X299687Y60393D03*
Y57243D03*
X291943Y166264D03*
Y169414D03*
X296523Y166264D03*
Y169414D03*
X294506Y341517D03*
Y344667D03*
X295509Y585487D03*
Y588637D03*
X294617Y1034882D03*
Y1038032D03*
X292698Y1112426D03*
Y1109276D03*
X293807Y1210314D03*
Y1213464D03*
X294133Y1287097D03*
Y1283947D03*
X298870Y1562451D03*
Y1565601D03*
X294392Y1562451D03*
Y1565601D03*
X294090Y1637318D03*
Y1634168D03*
X317567Y60393D03*
Y57243D03*
X322005Y60393D03*
Y57243D03*
X320045Y1987031D03*
Y1983881D03*
X324803Y1987031D03*
Y1983881D03*
G54D24*
X119920Y18071D03*
Y28071D03*
Y38071D03*
Y48071D03*
Y58071D03*
Y68071D03*
Y78071D03*
Y88071D03*
Y98071D03*
Y108071D03*
Y118071D03*
Y128071D03*
Y138071D03*
Y148071D03*
Y158071D03*
Y168071D03*
Y178071D03*
Y188071D03*
Y198071D03*
Y208071D03*
Y218071D03*
Y228071D03*
Y238071D03*
Y248071D03*
Y258071D03*
Y268071D03*
Y278071D03*
Y288071D03*
Y298071D03*
Y308071D03*
Y318071D03*
Y366102D03*
Y376102D03*
Y386102D03*
Y396102D03*
Y406102D03*
Y416102D03*
Y426102D03*
Y436102D03*
Y446102D03*
Y456102D03*
Y466102D03*
Y476102D03*
Y486102D03*
Y496102D03*
Y506102D03*
Y516102D03*
Y526102D03*
Y536102D03*
Y546102D03*
Y556102D03*
Y566102D03*
Y576102D03*
Y586102D03*
Y596102D03*
Y606102D03*
Y616102D03*
Y626102D03*
Y636102D03*
Y646102D03*
Y656102D03*
Y666102D03*
Y714134D03*
Y724134D03*
Y734134D03*
Y744134D03*
Y754134D03*
Y764134D03*
Y774134D03*
Y784134D03*
Y794134D03*
Y804134D03*
Y814134D03*
Y824134D03*
Y834134D03*
Y844134D03*
Y854134D03*
Y864134D03*
Y874134D03*
Y884134D03*
Y894134D03*
Y904134D03*
Y914134D03*
Y924134D03*
Y934134D03*
Y944134D03*
Y954134D03*
Y964134D03*
Y974134D03*
Y984134D03*
Y994134D03*
Y1004134D03*
Y1014134D03*
Y1062165D03*
Y1072165D03*
Y1082165D03*
Y1092165D03*
Y1102165D03*
Y1112165D03*
Y1122165D03*
Y1132165D03*
Y1142165D03*
Y1152165D03*
Y1162165D03*
Y1172165D03*
Y1182165D03*
Y1192165D03*
Y1202165D03*
Y1212165D03*
Y1222165D03*
Y1232165D03*
Y1242165D03*
Y1252165D03*
Y1262165D03*
Y1272165D03*
Y1282165D03*
Y1292165D03*
Y1302165D03*
Y1312165D03*
Y1322165D03*
Y1332165D03*
Y1342165D03*
Y1352165D03*
Y1362165D03*
Y1410197D03*
Y1420197D03*
Y1430197D03*
Y1440197D03*
Y1450197D03*
Y1460197D03*
Y1470197D03*
Y1480197D03*
Y1490197D03*
Y1500197D03*
Y1510197D03*
Y1520197D03*
Y1530197D03*
Y1540197D03*
Y1550197D03*
Y1560197D03*
Y1570197D03*
Y1580197D03*
Y1590197D03*
Y1600197D03*
Y1610197D03*
Y1620197D03*
Y1630197D03*
Y1640197D03*
Y1650197D03*
Y1660197D03*
Y1670197D03*
Y1680197D03*
Y1690197D03*
Y1700197D03*
Y1710197D03*
Y1758228D03*
Y1768228D03*
Y1778228D03*
Y1788228D03*
Y1798228D03*
Y1808228D03*
Y1818228D03*
Y1828228D03*
Y1838228D03*
Y1848228D03*
Y1858228D03*
Y1868228D03*
Y1878228D03*
Y1888228D03*
Y1898228D03*
Y1908228D03*
Y1918228D03*
Y1928228D03*
Y1938228D03*
Y1948228D03*
Y1958228D03*
Y1968228D03*
Y1978228D03*
Y1988228D03*
Y1998228D03*
Y2008228D03*
Y2018228D03*
Y2028228D03*
Y2038228D03*
Y2048228D03*
Y2058228D03*
X139920Y28071D03*
Y18071D03*
Y58071D03*
Y48071D03*
Y38071D03*
Y78071D03*
Y68071D03*
Y98071D03*
Y88071D03*
Y128071D03*
Y118071D03*
Y108071D03*
Y148071D03*
Y138071D03*
Y178071D03*
Y168071D03*
Y158071D03*
Y198071D03*
Y188071D03*
Y228071D03*
Y218071D03*
Y208071D03*
Y248071D03*
Y238071D03*
Y268071D03*
Y258071D03*
Y298071D03*
Y288071D03*
Y278071D03*
Y318071D03*
Y308071D03*
Y328071D03*
Y366102D03*
Y396102D03*
Y386102D03*
Y376102D03*
Y416102D03*
Y406102D03*
Y436102D03*
Y426102D03*
Y466102D03*
Y456102D03*
Y446102D03*
Y486102D03*
Y476102D03*
Y516102D03*
Y506102D03*
Y496102D03*
Y536102D03*
Y526102D03*
Y566102D03*
Y556102D03*
Y546102D03*
Y586102D03*
Y576102D03*
Y606102D03*
Y596102D03*
Y636102D03*
Y626102D03*
Y616102D03*
Y656102D03*
Y646102D03*
Y676102D03*
Y666102D03*
Y734134D03*
Y724134D03*
Y714134D03*
Y754134D03*
Y744134D03*
Y774134D03*
Y764134D03*
Y804134D03*
Y794134D03*
Y784134D03*
Y824134D03*
Y814134D03*
Y854134D03*
Y844134D03*
Y834134D03*
Y874134D03*
Y864134D03*
Y904134D03*
Y894134D03*
Y884134D03*
Y924134D03*
Y914134D03*
Y944134D03*
Y934134D03*
Y974134D03*
Y964134D03*
Y954134D03*
Y994134D03*
Y984134D03*
Y1024134D03*
Y1014134D03*
Y1004134D03*
Y1072165D03*
Y1062165D03*
Y1092165D03*
Y1082165D03*
Y1122165D03*
Y1112165D03*
Y1102165D03*
Y1142165D03*
Y1132165D03*
Y1162165D03*
Y1152165D03*
Y1192165D03*
Y1182165D03*
Y1172165D03*
Y1212165D03*
Y1202165D03*
Y1242165D03*
Y1232165D03*
Y1222165D03*
Y1262165D03*
Y1252165D03*
Y1282165D03*
Y1272165D03*
Y1312165D03*
Y1302165D03*
Y1292165D03*
Y1332165D03*
Y1322165D03*
Y1362165D03*
Y1352165D03*
Y1342165D03*
Y1372165D03*
Y1410197D03*
Y1430197D03*
Y1420197D03*
Y1460197D03*
Y1450197D03*
Y1440197D03*
Y1480197D03*
Y1470197D03*
Y1500197D03*
Y1490197D03*
Y1530197D03*
Y1520197D03*
Y1510197D03*
Y1550197D03*
Y1540197D03*
Y1580197D03*
Y1570197D03*
Y1560197D03*
Y1600197D03*
Y1590197D03*
Y1620197D03*
Y1610197D03*
Y1650197D03*
Y1640197D03*
Y1630197D03*
Y1670197D03*
Y1660197D03*
Y1700197D03*
Y1690197D03*
Y1680197D03*
Y1720197D03*
Y1710197D03*
Y1768228D03*
Y1758228D03*
Y1798228D03*
Y1788228D03*
Y1778228D03*
Y1818228D03*
Y1808228D03*
Y1838228D03*
Y1828228D03*
Y1868228D03*
Y1858228D03*
Y1848228D03*
Y1888228D03*
Y1878228D03*
Y1918228D03*
Y1908228D03*
Y1898228D03*
Y1938228D03*
Y1928228D03*
Y1958228D03*
Y1948228D03*
Y1988228D03*
Y1978228D03*
Y1968228D03*
Y2008228D03*
Y1998228D03*
Y2038228D03*
Y2028228D03*
Y2018228D03*
Y2058228D03*
Y2048228D03*
Y2068228D03*
G54D15*
X17480Y599901D03*
Y627264D03*
Y1471949D03*
Y1499311D03*
G54D25*
X119920Y328071D03*
Y676102D03*
Y1024134D03*
Y1372165D03*
Y1720197D03*
Y2068228D03*
G54D16*
X9606Y599901D03*
Y627264D03*
Y1471949D03*
Y1499311D03*
G54D26*
X271547Y235964D03*
Y241764D03*
X281569Y411540D03*
Y417340D03*
X285348Y586162D03*
Y591962D03*
X273114Y761236D03*
Y767036D03*
X275966Y934961D03*
Y940761D03*
X282958Y1109951D03*
Y1115751D03*
X283808Y1284622D03*
Y1290422D03*
X270234Y1458162D03*
Y1463962D03*
X284086Y1634843D03*
Y1640643D03*
X281066Y1809071D03*
Y1814871D03*
X294483Y57918D03*
Y63718D03*
X314562Y1983607D03*
Y1989407D03*
G54D17*
X18995Y1612992D03*
X53995Y518701D03*
G54D27*
G01X-723776Y2987387D02*
Y-376795D01*
Y-489221D01*
X1782976D01*
Y-376795D01*
Y2987387D01*
X-723776D01*
G01X-4000Y-62500D02*
Y-137500D01*
X496000D01*
Y-62500D01*
X-4000D01*
G01X8000Y-127500D02*
Y-132500D01*
G01X6543Y-127500D02*
X9457D01*
G01X14367Y-132500D02*
X11833D01*
Y-127500D01*
X14367D01*
G01X13353Y-129917D02*
X11833D01*
G01X16933Y-127500D02*
Y-132500D01*
X19467D01*
G01X23300Y-132667D02*
X23173Y-132583D01*
Y-132417D01*
X23300Y-132333D01*
X23427Y-132417D01*
Y-132583D01*
X23300Y-132667D01*
G01Y-130417D02*
X23173Y-130333D01*
Y-130167D01*
X23300Y-130083D01*
X23427Y-130167D01*
Y-130333D01*
X23300Y-130417D01*
G01X28083Y-134167D02*
X27450Y-133333D01*
X27133Y-132500D01*
Y-129167D01*
X27450Y-128333D01*
X28083Y-127500D01*
G01X33500D02*
X32993Y-127667D01*
X32613Y-128083D01*
X32360Y-128583D01*
X32170Y-129250D01*
X32107Y-130000D01*
X32170Y-130750D01*
X32360Y-131417D01*
X32613Y-131917D01*
X32993Y-132333D01*
X33500Y-132500D01*
X34007Y-132333D01*
X34387Y-131917D01*
X34640Y-131417D01*
X34830Y-130750D01*
X34893Y-130000D01*
X34830Y-129250D01*
X34640Y-128583D01*
X34387Y-128083D01*
X34007Y-127667D01*
X33500Y-127500D01*
G01X37207Y-131500D02*
X37587Y-132083D01*
X38093Y-132417D01*
X38663Y-132500D01*
X39170Y-132417D01*
X39677Y-132000D01*
X39993Y-131500D01*
X40057Y-131000D01*
X39930Y-130417D01*
X39487Y-130000D01*
X39043Y-129833D01*
X38473D01*
G01X39043D02*
X39423Y-129583D01*
X39740Y-129167D01*
X39867Y-128667D01*
X39740Y-128167D01*
X39423Y-127750D01*
X38853Y-127500D01*
X38283Y-127583D01*
X37713Y-127917D01*
G01X44017Y-134167D02*
X44650Y-133333D01*
X44967Y-132500D01*
Y-129167D01*
X44650Y-128333D01*
X44017Y-127500D01*
G01X47407Y-131500D02*
X47787Y-132083D01*
X48293Y-132417D01*
X48863Y-132500D01*
X49370Y-132417D01*
X49877Y-132000D01*
X50193Y-131500D01*
X50257Y-131000D01*
X50130Y-130417D01*
X49687Y-130000D01*
X49243Y-129833D01*
X48673D01*
G01X49243D02*
X49623Y-129583D01*
X49940Y-129167D01*
X50067Y-128667D01*
X49940Y-128167D01*
X49623Y-127750D01*
X49053Y-127500D01*
X48483Y-127583D01*
X47913Y-127917D01*
G01X52697Y-128333D02*
X53077Y-127833D01*
X53520Y-127583D01*
X54027Y-127500D01*
X54660Y-127667D01*
X55103Y-128083D01*
X55230Y-128583D01*
X55167Y-129083D01*
X54913Y-129500D01*
X53647Y-130333D01*
X53077Y-130917D01*
X52697Y-131750D01*
X52570Y-132500D01*
X55230D01*
G01X58873D02*
X59000Y-131417D01*
X59190Y-130500D01*
X59443Y-129667D01*
X59760Y-128750D01*
X60267Y-127500D01*
X57733D01*
G01X63277Y-130833D02*
X64923D01*
G01X67997Y-128333D02*
X68377Y-127833D01*
X68820Y-127583D01*
X69327Y-127500D01*
X69960Y-127667D01*
X70403Y-128083D01*
X70530Y-128583D01*
X70467Y-129083D01*
X70213Y-129500D01*
X68947Y-130333D01*
X68377Y-130917D01*
X67997Y-131750D01*
X67870Y-132500D01*
X70530D01*
G01X72907Y-131500D02*
X73287Y-132083D01*
X73793Y-132417D01*
X74363Y-132500D01*
X74870Y-132417D01*
X75377Y-132000D01*
X75693Y-131500D01*
X75757Y-131000D01*
X75630Y-130417D01*
X75187Y-130000D01*
X74743Y-129833D01*
X74173D01*
G01X74743D02*
X75123Y-129583D01*
X75440Y-129167D01*
X75567Y-128667D01*
X75440Y-128167D01*
X75123Y-127750D01*
X74553Y-127500D01*
X73983Y-127583D01*
X73413Y-127917D01*
G01X80160Y-132500D02*
Y-127500D01*
X77817Y-131083D01*
X80983D01*
G01X83107Y-131750D02*
X83487Y-132167D01*
X83930Y-132417D01*
X84500Y-132500D01*
X85070Y-132333D01*
X85513Y-132000D01*
X85830Y-131417D01*
X85893Y-130750D01*
X85767Y-130083D01*
X85450Y-129667D01*
X85007Y-129333D01*
X84563Y-129250D01*
X84120Y-129333D01*
X83550Y-129667D01*
X83740Y-127500D01*
X85450D01*
G01X93497Y-132500D02*
Y-127500D01*
X95903D01*
G01X95017Y-129917D02*
X93497D01*
G01X98217Y-132500D02*
X99800Y-127500D01*
X101383Y-132500D01*
G01X100813Y-130750D02*
X98787D01*
G01X103570Y-132500D02*
X106230Y-127500D01*
G01X103570D02*
X106230Y-132500D01*
G01X110000Y-132667D02*
X109873Y-132583D01*
Y-132417D01*
X110000Y-132333D01*
X110127Y-132417D01*
Y-132583D01*
X110000Y-132667D01*
G01Y-130417D02*
X109873Y-130333D01*
Y-130167D01*
X110000Y-130083D01*
X110127Y-130167D01*
Y-130333D01*
X110000Y-130417D01*
G01X114783Y-134167D02*
X114150Y-133333D01*
X113833Y-132500D01*
Y-129167D01*
X114150Y-128333D01*
X114783Y-127500D01*
G01X120200D02*
X119693Y-127667D01*
X119313Y-128083D01*
X119060Y-128583D01*
X118870Y-129250D01*
X118807Y-130000D01*
X118870Y-130750D01*
X119060Y-131417D01*
X119313Y-131917D01*
X119693Y-132333D01*
X120200Y-132500D01*
X120707Y-132333D01*
X121087Y-131917D01*
X121340Y-131417D01*
X121530Y-130750D01*
X121593Y-130000D01*
X121530Y-129250D01*
X121340Y-128583D01*
X121087Y-128083D01*
X120707Y-127667D01*
X120200Y-127500D01*
G01X123907Y-131500D02*
X124287Y-132083D01*
X124793Y-132417D01*
X125363Y-132500D01*
X125870Y-132417D01*
X126377Y-132000D01*
X126693Y-131500D01*
X126757Y-131000D01*
X126630Y-130417D01*
X126187Y-130000D01*
X125743Y-129833D01*
X125173D01*
G01X125743D02*
X126123Y-129583D01*
X126440Y-129167D01*
X126567Y-128667D01*
X126440Y-128167D01*
X126123Y-127750D01*
X125553Y-127500D01*
X124983Y-127583D01*
X124413Y-127917D01*
G01X130717Y-134167D02*
X131350Y-133333D01*
X131667Y-132500D01*
Y-129167D01*
X131350Y-128333D01*
X130717Y-127500D01*
G01X134107Y-131500D02*
X134487Y-132083D01*
X134993Y-132417D01*
X135563Y-132500D01*
X136070Y-132417D01*
X136577Y-132000D01*
X136893Y-131500D01*
X136957Y-131000D01*
X136830Y-130417D01*
X136387Y-130000D01*
X135943Y-129833D01*
X135373D01*
G01X135943D02*
X136323Y-129583D01*
X136640Y-129167D01*
X136767Y-128667D01*
X136640Y-128167D01*
X136323Y-127750D01*
X135753Y-127500D01*
X135183Y-127583D01*
X134613Y-127917D01*
G01X139523Y-131917D02*
X139967Y-132333D01*
X140473Y-132500D01*
X140980Y-132333D01*
X141423Y-131833D01*
X141740Y-131083D01*
X141867Y-130333D01*
Y-129417D01*
X141740Y-128667D01*
X141423Y-128000D01*
X141043Y-127667D01*
X140600Y-127500D01*
X140093Y-127667D01*
X139713Y-128000D01*
X139460Y-128500D01*
X139333Y-129167D01*
X139460Y-129750D01*
X139777Y-130333D01*
X140157Y-130667D01*
X140600Y-130750D01*
X141107Y-130583D01*
X141487Y-130167D01*
X141867Y-129417D01*
G01X145573Y-132500D02*
X145700Y-131417D01*
X145890Y-130500D01*
X146143Y-129667D01*
X146460Y-128750D01*
X146967Y-127500D01*
X144433D01*
G01X149977Y-130833D02*
X151623D01*
G01X154507Y-131500D02*
X154887Y-132083D01*
X155393Y-132417D01*
X155963Y-132500D01*
X156470Y-132417D01*
X156977Y-132000D01*
X157293Y-131500D01*
X157357Y-131000D01*
X157230Y-130417D01*
X156787Y-130000D01*
X156343Y-129833D01*
X155773D01*
G01X156343D02*
X156723Y-129583D01*
X157040Y-129167D01*
X157167Y-128667D01*
X157040Y-128167D01*
X156723Y-127750D01*
X156153Y-127500D01*
X155583Y-127583D01*
X155013Y-127917D01*
G01X159797Y-130417D02*
X160240Y-129833D01*
X160620Y-129500D01*
X161127Y-129333D01*
X161570Y-129500D01*
X161887Y-129833D01*
X162140Y-130333D01*
X162203Y-130917D01*
X162140Y-131417D01*
X161887Y-131917D01*
X161507Y-132333D01*
X161063Y-132500D01*
X160557Y-132333D01*
X160113Y-131833D01*
X159860Y-131083D01*
X159797Y-130250D01*
X159923Y-129167D01*
X160113Y-128583D01*
X160430Y-128000D01*
X160873Y-127583D01*
X161317Y-127500D01*
X161760Y-127667D01*
X162077Y-128083D01*
G01X166100Y-132500D02*
Y-127500D01*
X165340Y-128500D01*
G01Y-132500D02*
X166860D01*
G01X171960D02*
Y-127500D01*
X169617Y-131083D01*
X172783D01*
G01X191000Y-62500D02*
Y-137500D01*
G01Y-112500D02*
X294000D01*
Y-87500D01*
G01X191000D02*
X294000D01*
G01X301507Y-122500D02*
Y-117500D01*
X302773D01*
X303280Y-117750D01*
X303660Y-118083D01*
X303977Y-118583D01*
X304230Y-119167D01*
X304293Y-120000D01*
X304230Y-120833D01*
X303977Y-121417D01*
X303660Y-121917D01*
X303280Y-122250D01*
X302773Y-122500D01*
X301507D01*
G01X306417D02*
X308000Y-117500D01*
X309583Y-122500D01*
G01X309013Y-120750D02*
X306987D01*
G01X313100Y-117500D02*
Y-122500D01*
G01X311643Y-117500D02*
X314557D01*
G01X319467Y-122500D02*
X316933D01*
Y-117500D01*
X319467D01*
G01X318453Y-119917D02*
X316933D01*
G01X323300Y-122667D02*
X323173Y-122583D01*
Y-122417D01*
X323300Y-122333D01*
X323427Y-122417D01*
Y-122583D01*
X323300Y-122667D01*
G01Y-120417D02*
X323173Y-120333D01*
Y-120167D01*
X323300Y-120083D01*
X323427Y-120167D01*
Y-120333D01*
X323300Y-120417D01*
G01X296000Y-62500D02*
Y-137500D01*
G01X294000Y-62500D02*
Y-137500D01*
G01X301633Y-97500D02*
Y-92500D01*
X303153D01*
X303660Y-92750D01*
X304040Y-93333D01*
X304167Y-94000D01*
X304040Y-94667D01*
X303723Y-95167D01*
X303153Y-95417D01*
X301633D01*
G01X306860Y-97667D02*
X309140Y-92500D01*
G01X311643Y-97500D02*
Y-92500D01*
X314557Y-97500D01*
Y-92500D01*
G01X318200Y-97667D02*
X318073Y-97583D01*
Y-97417D01*
X318200Y-97333D01*
X318327Y-97417D01*
Y-97583D01*
X318200Y-97667D01*
G01Y-95417D02*
X318073Y-95333D01*
Y-95167D01*
X318200Y-95083D01*
X318327Y-95167D01*
Y-95333D01*
X318200Y-95417D01*
G01X296000Y-112500D02*
X496000D01*
G01X301633Y-72500D02*
Y-67500D01*
X303153D01*
X303660Y-67750D01*
X304040Y-68333D01*
X304167Y-69000D01*
X304040Y-69667D01*
X303723Y-70167D01*
X303153Y-70417D01*
X301633D01*
G01X306733Y-72500D02*
Y-67500D01*
X308317D01*
X308823Y-67750D01*
X309140Y-68083D01*
X309267Y-68750D01*
X309140Y-69417D01*
X308760Y-69833D01*
X308317Y-70083D01*
X306733D01*
G01X308317D02*
X309267Y-72500D01*
G01X313100D02*
X312593Y-72417D01*
X312150Y-72083D01*
X311770Y-71583D01*
X311517Y-71000D01*
X311390Y-70333D01*
Y-69667D01*
X311517Y-69000D01*
X311770Y-68417D01*
X312150Y-67917D01*
X312593Y-67583D01*
X313100Y-67500D01*
X313607Y-67583D01*
X314050Y-67917D01*
X314430Y-68417D01*
X314683Y-69000D01*
X314810Y-69667D01*
Y-70333D01*
X314683Y-71000D01*
X314430Y-71583D01*
X314050Y-72083D01*
X313607Y-72417D01*
X313100Y-72500D01*
G01X316933Y-71500D02*
X317250Y-72000D01*
X317630Y-72333D01*
X318073Y-72500D01*
X318580Y-72333D01*
X318960Y-72000D01*
X319340Y-71500D01*
X319467Y-70833D01*
Y-67500D01*
G01X324567Y-72500D02*
X322033D01*
Y-67500D01*
X324567D01*
G01X323553Y-69917D02*
X322033D01*
G01X329793Y-67917D02*
X329413Y-67667D01*
X328970Y-67500D01*
X328463D01*
X327893Y-67750D01*
X327450Y-68167D01*
X327133Y-68667D01*
X326880Y-69500D01*
X326817Y-70250D01*
X326943Y-71000D01*
X327133Y-71500D01*
X327513Y-72000D01*
X327957Y-72333D01*
X328400Y-72500D01*
X328843D01*
X329287Y-72333D01*
X329667Y-72083D01*
X329983Y-71750D01*
G01X333500Y-67500D02*
Y-72500D01*
G01X332043Y-67500D02*
X334957D01*
G01X338600Y-72667D02*
X338473Y-72583D01*
Y-72417D01*
X338600Y-72333D01*
X338727Y-72417D01*
Y-72583D01*
X338600Y-72667D01*
G01Y-70417D02*
X338473Y-70333D01*
Y-70167D01*
X338600Y-70083D01*
X338727Y-70167D01*
Y-70333D01*
X338600Y-70417D01*
G01X296000Y-87500D02*
X496000D01*
G01X411000Y-112500D02*
Y-137500D01*
G01X416633Y-122500D02*
Y-117500D01*
X418217D01*
X418723Y-117750D01*
X419040Y-118083D01*
X419167Y-118750D01*
X419040Y-119417D01*
X418660Y-119833D01*
X418217Y-120083D01*
X416633D01*
G01X418217D02*
X419167Y-122500D01*
G01X424267D02*
X421733D01*
Y-117500D01*
X424267D01*
G01X423253Y-119917D02*
X421733D01*
G01X426517Y-117500D02*
X428100Y-122500D01*
X429683Y-117500D01*
G01X433200Y-122667D02*
X433073Y-122583D01*
Y-122417D01*
X433200Y-122333D01*
X433327Y-122417D01*
Y-122583D01*
X433200Y-122667D01*
G01Y-120417D02*
X433073Y-120333D01*
Y-120167D01*
X433200Y-120083D01*
X433327Y-120167D01*
Y-120333D01*
X433200Y-120417D01*
G01X460000Y-112500D02*
Y-137500D01*
G01X-723776Y2987387D02*
Y-376795D01*
Y-489221D01*
X1782976D01*
Y-376795D01*
Y2987387D01*
X-723776D01*
G01X6705Y-124160D02*
X7332Y-124685D01*
X8037Y-125000D01*
X8663D01*
X9290Y-124685D01*
X9760Y-124160D01*
X9995Y-123425D01*
X9838Y-122690D01*
X9447Y-122060D01*
X8742Y-121640D01*
X7802Y-121430D01*
X7253Y-121010D01*
X7018Y-120275D01*
X7175Y-119540D01*
X7567Y-119015D01*
X8115Y-118700D01*
X8663D01*
X9212Y-118910D01*
X9682Y-119435D01*
G01X13005Y-125000D02*
Y-118700D01*
G01X16295D02*
Y-125000D01*
G01Y-121850D02*
X13005D01*
G01X20010Y-118700D02*
X21890D01*
G01X20950D02*
Y-125000D01*
G01X20010D02*
X21890D01*
G01X28817D02*
X25683D01*
Y-118700D01*
X28817D01*
G01X27563Y-121745D02*
X25683D01*
G01X31748Y-125000D02*
Y-118700D01*
X35352Y-125000D01*
Y-118700D01*
G01X39693Y-126155D02*
X40007Y-124790D01*
G01X46150Y-118700D02*
Y-125000D01*
G01X44348Y-118700D02*
X47952D01*
G01X50492Y-125000D02*
X52450Y-118700D01*
X54408Y-125000D01*
G01X53703Y-122795D02*
X51197D01*
G01X57810Y-118700D02*
X59690D01*
G01X58750D02*
Y-125000D01*
G01X57810D02*
X59690D01*
G01X62700Y-118700D02*
X63797Y-125000D01*
X65050Y-118700D01*
X66303Y-125000D01*
X67400Y-118700D01*
G01X69392Y-125000D02*
X71350Y-118700D01*
X73308Y-125000D01*
G01X72603Y-122795D02*
X70097D01*
G01X75848Y-125000D02*
Y-118700D01*
X79452Y-125000D01*
Y-118700D01*
G01X88683Y-125000D02*
Y-118700D01*
X90642D01*
X91268Y-119015D01*
X91660Y-119435D01*
X91817Y-120275D01*
X91660Y-121115D01*
X91190Y-121640D01*
X90642Y-121955D01*
X88683D01*
G01X90642D02*
X91817Y-125000D01*
G01X96550Y-125210D02*
X96393Y-125105D01*
Y-124895D01*
X96550Y-124790D01*
X96707Y-124895D01*
Y-125105D01*
X96550Y-125210D01*
G01X102850Y-125000D02*
X102223Y-124895D01*
X101675Y-124475D01*
X101205Y-123845D01*
X100892Y-123110D01*
X100735Y-122270D01*
Y-121430D01*
X100892Y-120590D01*
X101205Y-119855D01*
X101675Y-119225D01*
X102223Y-118805D01*
X102850Y-118700D01*
X103477Y-118805D01*
X104025Y-119225D01*
X104495Y-119855D01*
X104808Y-120590D01*
X104965Y-121430D01*
Y-122270D01*
X104808Y-123110D01*
X104495Y-123845D01*
X104025Y-124475D01*
X103477Y-124895D01*
X102850Y-125000D01*
G01X109150Y-125210D02*
X108993Y-125105D01*
Y-124895D01*
X109150Y-124790D01*
X109307Y-124895D01*
Y-125105D01*
X109150Y-125210D01*
G01X117173Y-119225D02*
X116703Y-118910D01*
X116155Y-118700D01*
X115528D01*
X114823Y-119015D01*
X114275Y-119540D01*
X113883Y-120170D01*
X113570Y-121220D01*
X113492Y-122165D01*
X113648Y-123110D01*
X113883Y-123740D01*
X114353Y-124370D01*
X114902Y-124790D01*
X115450Y-125000D01*
X115998D01*
X116547Y-124790D01*
X117017Y-124475D01*
X117408Y-124055D01*
G01X121750Y-125210D02*
X121593Y-125105D01*
Y-124895D01*
X121750Y-124790D01*
X121907Y-124895D01*
Y-125105D01*
X121750Y-125210D01*
G01X6627Y-115000D02*
Y-108700D01*
G01X9603D02*
X6627Y-112585D01*
G01X10073Y-115000D02*
X7958Y-110800D01*
G01X12927Y-108700D02*
Y-113215D01*
X13240Y-114160D01*
X13867Y-114790D01*
X14650Y-115000D01*
X15433Y-114790D01*
X16060Y-114160D01*
X16373Y-113215D01*
Y-108700D01*
G01X22517Y-115000D02*
X19383D01*
Y-108700D01*
X22517D01*
G01X21263Y-111745D02*
X19383D01*
G01X26310Y-108700D02*
X28190D01*
G01X27250D02*
Y-115000D01*
G01X26310D02*
X28190D01*
G01X38205Y-114160D02*
X38832Y-114685D01*
X39537Y-115000D01*
X40163D01*
X40790Y-114685D01*
X41260Y-114160D01*
X41495Y-113425D01*
X41338Y-112690D01*
X40947Y-112060D01*
X40242Y-111640D01*
X39302Y-111430D01*
X38753Y-111010D01*
X38518Y-110275D01*
X38675Y-109540D01*
X39067Y-109015D01*
X39615Y-108700D01*
X40163D01*
X40712Y-108910D01*
X41182Y-109435D01*
G01X44505Y-115000D02*
Y-108700D01*
G01X47795D02*
Y-115000D01*
G01Y-111850D02*
X44505D01*
G01X50492Y-115000D02*
X52450Y-108700D01*
X54408Y-115000D01*
G01X53703Y-112795D02*
X51197D01*
G01X56948Y-115000D02*
Y-108700D01*
X60552Y-115000D01*
Y-108700D01*
G01X69705Y-115000D02*
Y-108700D01*
G01X72995D02*
Y-115000D01*
G01Y-111850D02*
X69705D01*
G01X76005Y-114160D02*
X76632Y-114685D01*
X77337Y-115000D01*
X77963D01*
X78590Y-114685D01*
X79060Y-114160D01*
X79295Y-113425D01*
X79138Y-112690D01*
X78747Y-112060D01*
X78042Y-111640D01*
X77102Y-111430D01*
X76553Y-111010D01*
X76318Y-110275D01*
X76475Y-109540D01*
X76867Y-109015D01*
X77415Y-108700D01*
X77963D01*
X78512Y-108910D01*
X78982Y-109435D01*
G01X83010Y-108700D02*
X84890D01*
G01X83950D02*
Y-115000D01*
G01X83010D02*
X84890D01*
G01X88292D02*
X90250Y-108700D01*
X92208Y-115000D01*
G01X91503Y-112795D02*
X88997D01*
G01X94748Y-115000D02*
Y-108700D01*
X98352Y-115000D01*
Y-108700D01*
G01X103320Y-111850D02*
X104887D01*
Y-113740D01*
X104417Y-114370D01*
X103868Y-114790D01*
X103085Y-115000D01*
X102302Y-114790D01*
X101753Y-114370D01*
X101283Y-113740D01*
X100970Y-113005D01*
X100813Y-112165D01*
Y-111430D01*
X100970Y-110800D01*
X101283Y-110065D01*
X101753Y-109435D01*
X102223Y-109015D01*
X102850Y-108700D01*
X103398D01*
X104025Y-108910D01*
X104495Y-109330D01*
G01X108993Y-116155D02*
X109307Y-114790D01*
G01X115450Y-108700D02*
Y-115000D01*
G01X113648Y-108700D02*
X117252D01*
G01X119792Y-115000D02*
X121750Y-108700D01*
X123708Y-115000D01*
G01X123003Y-112795D02*
X120497D01*
G01X128050Y-115000D02*
X127423Y-114895D01*
X126875Y-114475D01*
X126405Y-113845D01*
X126092Y-113110D01*
X125935Y-112270D01*
Y-111430D01*
X126092Y-110590D01*
X126405Y-109855D01*
X126875Y-109225D01*
X127423Y-108805D01*
X128050Y-108700D01*
X128677Y-108805D01*
X129225Y-109225D01*
X129695Y-109855D01*
X130008Y-110590D01*
X130165Y-111430D01*
Y-112270D01*
X130008Y-113110D01*
X129695Y-113845D01*
X129225Y-114475D01*
X128677Y-114895D01*
X128050Y-115000D01*
G01X140650D02*
Y-112165D01*
X139083Y-108700D01*
G01X142217D02*
X140650Y-112165D01*
G01X145227Y-108700D02*
Y-113215D01*
X145540Y-114160D01*
X146167Y-114790D01*
X146950Y-115000D01*
X147733Y-114790D01*
X148360Y-114160D01*
X148673Y-113215D01*
Y-108700D01*
G01X151292Y-115000D02*
X153250Y-108700D01*
X155208Y-115000D01*
G01X154503Y-112795D02*
X151997D01*
G01X157748Y-115000D02*
Y-108700D01*
X161352Y-115000D01*
Y-108700D01*
G01X30650Y-92300D02*
X28130Y-91883D01*
X25925Y-90217D01*
X24035Y-87717D01*
X22775Y-84800D01*
X22145Y-81467D01*
Y-78133D01*
X22775Y-74800D01*
X24035Y-71883D01*
X25925Y-69384D01*
X28130Y-67717D01*
X30650Y-67300D01*
X33170Y-67717D01*
X35375Y-69384D01*
X37265Y-71883D01*
X38525Y-74800D01*
X39155Y-78133D01*
Y-81467D01*
X38525Y-84800D01*
X37265Y-87717D01*
X35375Y-90217D01*
X33170Y-91883D01*
X30650Y-92300D01*
G01X33170Y-85633D02*
X36950Y-92300D01*
G01X50495Y-75634D02*
Y-87300D01*
X51755Y-90217D01*
X53645Y-91883D01*
X55850Y-92300D01*
X58055Y-91883D01*
X59945Y-90217D01*
X61205Y-87300D01*
G01Y-92300D02*
Y-75634D01*
G01X86720Y-92300D02*
Y-75634D01*
G01Y-78550D02*
X85460Y-76884D01*
X83570Y-76050D01*
X81365Y-75634D01*
X79160Y-76467D01*
X77270Y-78133D01*
X76010Y-80634D01*
X75380Y-83967D01*
X76010Y-87300D01*
X77270Y-89801D01*
X79160Y-91467D01*
X81365Y-92300D01*
X83570Y-91883D01*
X85460Y-90634D01*
X86720Y-88967D01*
G01X100895Y-92300D02*
Y-75634D01*
G01Y-79800D02*
X102155Y-77717D01*
X104045Y-76050D01*
X106565Y-75634D01*
X108770Y-76050D01*
X110660Y-77717D01*
X111605Y-80634D01*
Y-92300D01*
G01X131450Y-67300D02*
Y-92300D01*
G01X127040Y-75634D02*
X135860D01*
G01X162320Y-92300D02*
Y-75634D01*
G01Y-78550D02*
X161060Y-76884D01*
X159170Y-76050D01*
X156965Y-75634D01*
X154760Y-76467D01*
X152870Y-78133D01*
X151610Y-80634D01*
X150980Y-83967D01*
X151610Y-87300D01*
X152870Y-89801D01*
X154760Y-91467D01*
X156965Y-92300D01*
X159170Y-91883D01*
X161060Y-90634D01*
X162320Y-88967D01*
G01X6548Y-105000D02*
Y-98700D01*
X10152Y-105000D01*
Y-98700D01*
G01X14650Y-105000D02*
X14023Y-104895D01*
X13475Y-104475D01*
X13005Y-103845D01*
X12692Y-103110D01*
X12535Y-102270D01*
Y-101430D01*
X12692Y-100590D01*
X13005Y-99855D01*
X13475Y-99225D01*
X14023Y-98805D01*
X14650Y-98700D01*
X15277Y-98805D01*
X15825Y-99225D01*
X16295Y-99855D01*
X16608Y-100590D01*
X16765Y-101430D01*
Y-102270D01*
X16608Y-103110D01*
X16295Y-103845D01*
X15825Y-104475D01*
X15277Y-104895D01*
X14650Y-105000D01*
G01X20950Y-105210D02*
X20793Y-105105D01*
Y-104895D01*
X20950Y-104790D01*
X21107Y-104895D01*
Y-105105D01*
X20950Y-105210D01*
G01X27250Y-105000D02*
Y-98700D01*
X26310Y-99960D01*
G01Y-105000D02*
X28190D01*
G01X33550D02*
X34098Y-104895D01*
X34725Y-104580D01*
X35117Y-104055D01*
X35273Y-103320D01*
X35117Y-102585D01*
X34647Y-101955D01*
X33942Y-101640D01*
X33158D01*
X32688Y-101430D01*
X32297Y-100905D01*
X32140Y-100170D01*
X32375Y-99435D01*
X32923Y-98910D01*
X33550Y-98700D01*
X34177Y-98910D01*
X34725Y-99435D01*
X34960Y-100170D01*
X34803Y-100905D01*
X34412Y-101430D01*
X33942Y-101640D01*
X33158D01*
X32453Y-101955D01*
X31983Y-102585D01*
X31827Y-103320D01*
X31983Y-104055D01*
X32375Y-104580D01*
X33002Y-104895D01*
X33550Y-105000D01*
G01X39850D02*
X40398Y-104895D01*
X41025Y-104580D01*
X41417Y-104055D01*
X41573Y-103320D01*
X41417Y-102585D01*
X40947Y-101955D01*
X40242Y-101640D01*
X39458D01*
X38988Y-101430D01*
X38597Y-100905D01*
X38440Y-100170D01*
X38675Y-99435D01*
X39223Y-98910D01*
X39850Y-98700D01*
X40477Y-98910D01*
X41025Y-99435D01*
X41260Y-100170D01*
X41103Y-100905D01*
X40712Y-101430D01*
X40242Y-101640D01*
X39458D01*
X38753Y-101955D01*
X38283Y-102585D01*
X38127Y-103320D01*
X38283Y-104055D01*
X38675Y-104580D01*
X39302Y-104895D01*
X39850Y-105000D01*
G01X45993Y-106155D02*
X46307Y-104790D01*
G01X50100Y-98700D02*
X51197Y-105000D01*
X52450Y-98700D01*
X53703Y-105000D01*
X54800Y-98700D01*
G01X60317Y-105000D02*
X57183D01*
Y-98700D01*
X60317D01*
G01X59063Y-101745D02*
X57183D01*
G01X63248Y-105000D02*
Y-98700D01*
X66852Y-105000D01*
Y-98700D01*
G01X76005Y-105000D02*
Y-98700D01*
G01X79295D02*
Y-105000D01*
G01Y-101850D02*
X76005D01*
G01X81600Y-98700D02*
X82697Y-105000D01*
X83950Y-98700D01*
X85203Y-105000D01*
X86300Y-98700D01*
G01X88292Y-105000D02*
X90250Y-98700D01*
X92208Y-105000D01*
G01X91503Y-102795D02*
X88997D01*
G01X101362Y-99750D02*
X101832Y-99120D01*
X102380Y-98805D01*
X103007Y-98700D01*
X103790Y-98910D01*
X104338Y-99435D01*
X104495Y-100065D01*
X104417Y-100695D01*
X104103Y-101220D01*
X102537Y-102270D01*
X101832Y-103005D01*
X101362Y-104055D01*
X101205Y-105000D01*
X104495D01*
G01X107348D02*
Y-98700D01*
X110952Y-105000D01*
Y-98700D01*
G01X113727Y-105000D02*
Y-98700D01*
X115293D01*
X115920Y-99015D01*
X116390Y-99435D01*
X116782Y-100065D01*
X117095Y-100800D01*
X117173Y-101850D01*
X117095Y-102900D01*
X116782Y-103635D01*
X116390Y-104265D01*
X115920Y-104685D01*
X115293Y-105000D01*
X113727D01*
G01X126483D02*
Y-98700D01*
X128442D01*
X129068Y-99015D01*
X129460Y-99435D01*
X129617Y-100275D01*
X129460Y-101115D01*
X128990Y-101640D01*
X128442Y-101955D01*
X126483D01*
G01X128442D02*
X129617Y-105000D01*
G01X132627D02*
Y-98700D01*
X134193D01*
X134820Y-99015D01*
X135290Y-99435D01*
X135682Y-100065D01*
X135995Y-100800D01*
X136073Y-101850D01*
X135995Y-102900D01*
X135682Y-103635D01*
X135290Y-104265D01*
X134820Y-104685D01*
X134193Y-105000D01*
X132627D01*
G01X140650Y-105210D02*
X140493Y-105105D01*
Y-104895D01*
X140650Y-104790D01*
X140807Y-104895D01*
Y-105105D01*
X140650Y-105210D01*
G01X213500Y-105000D02*
Y-97000D01*
X215900D01*
X216700Y-97400D01*
X217300Y-98333D01*
X217500Y-99400D01*
X217300Y-100467D01*
X216800Y-101267D01*
X215900Y-101667D01*
X213500D01*
G01X221000Y-105000D02*
X223500Y-97000D01*
X226000Y-105000D01*
G01X225100Y-102200D02*
X221900D01*
G01X229400Y-103934D02*
X230200Y-104600D01*
X231100Y-105000D01*
X231900D01*
X232700Y-104600D01*
X233300Y-103934D01*
X233600Y-103000D01*
X233400Y-102067D01*
X232900Y-101267D01*
X232000Y-100733D01*
X230800Y-100467D01*
X230100Y-99933D01*
X229800Y-99000D01*
X230000Y-98067D01*
X230500Y-97400D01*
X231200Y-97000D01*
X231900D01*
X232600Y-97267D01*
X233200Y-97933D01*
G01X239500Y-97000D02*
Y-105000D01*
G01X237200Y-97000D02*
X241800D01*
G01X246200Y-102333D02*
X248800D01*
G01X255500Y-97000D02*
Y-105000D01*
G01X253200Y-97000D02*
X257800D01*
G01X263500Y-105000D02*
X262700Y-104867D01*
X262000Y-104333D01*
X261400Y-103533D01*
X261000Y-102600D01*
X260800Y-101533D01*
Y-100467D01*
X261000Y-99400D01*
X261400Y-98467D01*
X262000Y-97667D01*
X262700Y-97133D01*
X263500Y-97000D01*
X264300Y-97133D01*
X265000Y-97667D01*
X265600Y-98467D01*
X266000Y-99400D01*
X266200Y-100467D01*
Y-101533D01*
X266000Y-102600D01*
X265600Y-103533D01*
X265000Y-104333D01*
X264300Y-104867D01*
X263500Y-105000D01*
G01X269500D02*
Y-97000D01*
X271900D01*
X272700Y-97400D01*
X273300Y-98333D01*
X273500Y-99400D01*
X273300Y-100467D01*
X272800Y-101267D01*
X271900Y-101667D01*
X269500D01*
G01X202000Y-72000D02*
Y-80000D01*
X206000D01*
G01X213800D02*
Y-74667D01*
G01Y-75600D02*
X213400Y-75067D01*
X212800Y-74800D01*
X212100Y-74667D01*
X211400Y-74933D01*
X210800Y-75467D01*
X210400Y-76267D01*
X210200Y-77333D01*
X210400Y-78400D01*
X210800Y-79200D01*
X211400Y-79733D01*
X212100Y-80000D01*
X212800Y-79867D01*
X213400Y-79467D01*
X213800Y-78934D01*
G01X217900Y-82400D02*
X218500Y-82667D01*
X219300Y-82400D01*
X219800Y-81867D01*
X220200Y-81200D01*
X220800Y-79067D01*
X222100Y-74667D01*
G01X218900D02*
X220800Y-79067D01*
G01X226500Y-76400D02*
X229700D01*
X229400Y-75467D01*
X228900Y-74933D01*
X228200Y-74667D01*
X227500Y-74800D01*
X226900Y-75200D01*
X226500Y-76133D01*
X226300Y-76934D01*
Y-77733D01*
X226500Y-78533D01*
X227000Y-79333D01*
X227600Y-79867D01*
X228300Y-80000D01*
X229000Y-79733D01*
X229700Y-78934D01*
G01X234600Y-80000D02*
Y-74667D01*
G01Y-75733D02*
X235100Y-75200D01*
X235600Y-74800D01*
X236300Y-74667D01*
X236800Y-74800D01*
X237400Y-75200D01*
G01X223400Y-128934D02*
X224200Y-129600D01*
X225100Y-130000D01*
X225900D01*
X226700Y-129600D01*
X227300Y-128934D01*
X227600Y-128000D01*
X227400Y-127067D01*
X226900Y-126267D01*
X226000Y-125733D01*
X224800Y-125467D01*
X224100Y-124933D01*
X223800Y-124000D01*
X224000Y-123067D01*
X224500Y-122400D01*
X225200Y-122000D01*
X225900D01*
X226600Y-122267D01*
X227200Y-122933D01*
G01X235300Y-130000D02*
Y-124667D01*
G01Y-125600D02*
X234900Y-125067D01*
X234300Y-124800D01*
X233600Y-124667D01*
X232900Y-124933D01*
X232300Y-125467D01*
X231900Y-126267D01*
X231700Y-127333D01*
X231900Y-128400D01*
X232300Y-129200D01*
X232900Y-129733D01*
X233600Y-130000D01*
X234300Y-129867D01*
X234900Y-129467D01*
X235300Y-128934D01*
G01X239800Y-130000D02*
Y-124667D01*
G01Y-126000D02*
X240200Y-125333D01*
X240800Y-124800D01*
X241600Y-124667D01*
X242300Y-124800D01*
X242900Y-125333D01*
X243200Y-126267D01*
Y-130000D01*
G01X251300Y-122000D02*
Y-130000D01*
G01Y-128800D02*
X250900Y-129467D01*
X250300Y-129867D01*
X249600Y-130000D01*
X248800Y-129733D01*
X248200Y-129067D01*
X247800Y-128267D01*
X247700Y-127333D01*
X247800Y-126400D01*
X248200Y-125600D01*
X248800Y-124933D01*
X249600Y-124667D01*
X250300Y-124800D01*
X250800Y-125067D01*
X251300Y-125600D01*
G01X255400Y-132400D02*
X256000Y-132667D01*
X256800Y-132400D01*
X257300Y-131867D01*
X257700Y-131200D01*
X258300Y-129067D01*
X259600Y-124667D01*
G01X256400D02*
X258300Y-129067D01*
G01X328600Y-123333D02*
X329200Y-122533D01*
X329900Y-122133D01*
X330700Y-122000D01*
X331700Y-122267D01*
X332400Y-122933D01*
X332600Y-123733D01*
X332500Y-124534D01*
X332100Y-125200D01*
X330100Y-126533D01*
X329200Y-127467D01*
X328600Y-128800D01*
X328400Y-130000D01*
X332600D01*
G01X338500Y-122000D02*
X337700Y-122267D01*
X337100Y-122933D01*
X336700Y-123733D01*
X336400Y-124800D01*
X336300Y-126000D01*
X336400Y-127200D01*
X336700Y-128267D01*
X337100Y-129067D01*
X337700Y-129733D01*
X338500Y-130000D01*
X339300Y-129733D01*
X339900Y-129067D01*
X340300Y-128267D01*
X340600Y-127200D01*
X340700Y-126000D01*
X340600Y-124800D01*
X340300Y-123733D01*
X339900Y-122933D01*
X339300Y-122267D01*
X338500Y-122000D01*
G01X346500Y-130000D02*
Y-122000D01*
X345300Y-123600D01*
G01Y-130000D02*
X347700D01*
G01X352600Y-123333D02*
X353200Y-122533D01*
X353900Y-122133D01*
X354700Y-122000D01*
X355700Y-122267D01*
X356400Y-122933D01*
X356600Y-123733D01*
X356500Y-124534D01*
X356100Y-125200D01*
X354100Y-126533D01*
X353200Y-127467D01*
X352600Y-128800D01*
X352400Y-130000D01*
X356600D01*
G01X360700Y-130267D02*
X364300Y-122000D01*
G01X370500D02*
X369700Y-122267D01*
X369100Y-122933D01*
X368700Y-123733D01*
X368400Y-124800D01*
X368300Y-126000D01*
X368400Y-127200D01*
X368700Y-128267D01*
X369100Y-129067D01*
X369700Y-129733D01*
X370500Y-130000D01*
X371300Y-129733D01*
X371900Y-129067D01*
X372300Y-128267D01*
X372600Y-127200D01*
X372700Y-126000D01*
X372600Y-124800D01*
X372300Y-123733D01*
X371900Y-122933D01*
X371300Y-122267D01*
X370500Y-122000D01*
G01X376800Y-129067D02*
X377500Y-129733D01*
X378300Y-130000D01*
X379100Y-129733D01*
X379800Y-128934D01*
X380300Y-127733D01*
X380500Y-126533D01*
Y-125067D01*
X380300Y-123867D01*
X379800Y-122800D01*
X379200Y-122267D01*
X378500Y-122000D01*
X377700Y-122267D01*
X377100Y-122800D01*
X376700Y-123600D01*
X376500Y-124667D01*
X376700Y-125600D01*
X377200Y-126533D01*
X377800Y-127067D01*
X378500Y-127200D01*
X379300Y-126934D01*
X379900Y-126267D01*
X380500Y-125067D01*
G01X384700Y-130267D02*
X388300Y-122000D01*
G01X392600Y-123333D02*
X393200Y-122533D01*
X393900Y-122133D01*
X394700Y-122000D01*
X395700Y-122267D01*
X396400Y-122933D01*
X396600Y-123733D01*
X396500Y-124534D01*
X396100Y-125200D01*
X394100Y-126533D01*
X393200Y-127467D01*
X392600Y-128800D01*
X392400Y-130000D01*
X396600D01*
G01X402500D02*
X403200Y-129867D01*
X404000Y-129467D01*
X404500Y-128800D01*
X404700Y-127867D01*
X404500Y-126934D01*
X403900Y-126133D01*
X403000Y-125733D01*
X402000D01*
X401400Y-125467D01*
X400900Y-124800D01*
X400700Y-123867D01*
X401000Y-122933D01*
X401700Y-122267D01*
X402500Y-122000D01*
X403300Y-122267D01*
X404000Y-122933D01*
X404300Y-123867D01*
X404100Y-124800D01*
X403600Y-125467D01*
X403000Y-125733D01*
X402000D01*
X401100Y-126133D01*
X400500Y-126934D01*
X400300Y-127867D01*
X400500Y-128800D01*
X401000Y-129467D01*
X401800Y-129867D01*
X402500Y-130000D01*
G01X328300Y-105000D02*
Y-97000D01*
X330300D01*
X331100Y-97400D01*
X331700Y-97933D01*
X332200Y-98733D01*
X332600Y-99667D01*
X332700Y-101000D01*
X332600Y-102333D01*
X332200Y-103267D01*
X331700Y-104067D01*
X331100Y-104600D01*
X330300Y-105000D01*
X328300D01*
G01X336000D02*
X338500Y-97000D01*
X341000Y-105000D01*
G01X340100Y-102200D02*
X336900D01*
G01X346500Y-97000D02*
X345700Y-97267D01*
X345100Y-97933D01*
X344700Y-98733D01*
X344400Y-99800D01*
X344300Y-101000D01*
X344400Y-102200D01*
X344700Y-103267D01*
X345100Y-104067D01*
X345700Y-104733D01*
X346500Y-105000D01*
X347300Y-104733D01*
X347900Y-104067D01*
X348300Y-103267D01*
X348600Y-102200D01*
X348700Y-101000D01*
X348600Y-99800D01*
X348300Y-98733D01*
X347900Y-97933D01*
X347300Y-97267D01*
X346500Y-97000D01*
G01X354500D02*
Y-105000D01*
G01X352200Y-97000D02*
X356800D01*
G01X360600Y-101667D02*
X361300Y-100733D01*
X361900Y-100200D01*
X362700Y-99933D01*
X363400Y-100200D01*
X363900Y-100733D01*
X364300Y-101533D01*
X364400Y-102467D01*
X364300Y-103267D01*
X363900Y-104067D01*
X363300Y-104733D01*
X362600Y-105000D01*
X361800Y-104733D01*
X361100Y-103934D01*
X360700Y-102733D01*
X360600Y-101400D01*
X360800Y-99667D01*
X361100Y-98733D01*
X361600Y-97800D01*
X362300Y-97133D01*
X363000Y-97000D01*
X363700Y-97267D01*
X364200Y-97933D01*
G01X367900Y-105000D02*
Y-97000D01*
X370500Y-103667D01*
X373100Y-97000D01*
Y-105000D01*
G01X378500Y-97000D02*
Y-105000D01*
G01X376200Y-97000D02*
X380800D01*
G01X387300Y-100733D02*
X387700Y-100333D01*
X388000Y-99667D01*
X388200Y-98733D01*
X388000Y-97933D01*
X387600Y-97400D01*
X386900Y-97000D01*
X384200D01*
Y-105000D01*
X387500D01*
X388200Y-104467D01*
X388600Y-103667D01*
X388800Y-102733D01*
X388600Y-101800D01*
X388000Y-101000D01*
X387300Y-100733D01*
X384200D01*
G01X394500Y-105000D02*
X395200Y-104867D01*
X396000Y-104467D01*
X396500Y-103800D01*
X396700Y-102867D01*
X396500Y-101934D01*
X395900Y-101133D01*
X395000Y-100733D01*
X394000D01*
X393400Y-100467D01*
X392900Y-99800D01*
X392700Y-98867D01*
X393000Y-97933D01*
X393700Y-97267D01*
X394500Y-97000D01*
X395300Y-97267D01*
X396000Y-97933D01*
X396300Y-98867D01*
X396100Y-99800D01*
X395600Y-100467D01*
X395000Y-100733D01*
X394000D01*
X393100Y-101133D01*
X392500Y-101934D01*
X392300Y-102867D01*
X392500Y-103800D01*
X393000Y-104467D01*
X393800Y-104867D01*
X394500Y-105000D01*
G01X400300D02*
Y-97000D01*
X402300D01*
X403100Y-97400D01*
X403700Y-97933D01*
X404200Y-98733D01*
X404600Y-99667D01*
X404700Y-101000D01*
X404600Y-102333D01*
X404200Y-103267D01*
X403700Y-104067D01*
X403100Y-104600D01*
X402300Y-105000D01*
X400300D01*
G01X410500Y-97000D02*
X409700Y-97267D01*
X409100Y-97933D01*
X408700Y-98733D01*
X408400Y-99800D01*
X408300Y-101000D01*
X408400Y-102200D01*
X408700Y-103267D01*
X409100Y-104067D01*
X409700Y-104733D01*
X410500Y-105000D01*
X411300Y-104733D01*
X411900Y-104067D01*
X412300Y-103267D01*
X412600Y-102200D01*
X412700Y-101000D01*
X412600Y-99800D01*
X412300Y-98733D01*
X411900Y-97933D01*
X411300Y-97267D01*
X410500Y-97000D01*
G01X350500Y-72000D02*
Y-80000D01*
G01X348200Y-72000D02*
X352800D01*
G01X356600Y-76667D02*
X357300Y-75733D01*
X357900Y-75200D01*
X358700Y-74933D01*
X359400Y-75200D01*
X359900Y-75733D01*
X360300Y-76533D01*
X360400Y-77467D01*
X360300Y-78267D01*
X359900Y-79067D01*
X359300Y-79733D01*
X358600Y-80000D01*
X357800Y-79733D01*
X357100Y-78934D01*
X356700Y-77733D01*
X356600Y-76400D01*
X356800Y-74667D01*
X357100Y-73733D01*
X357600Y-72800D01*
X358300Y-72133D01*
X359000Y-72000D01*
X359700Y-72267D01*
X360200Y-72933D01*
G01X363900Y-80000D02*
Y-72000D01*
X366500Y-78667D01*
X369100Y-72000D01*
Y-80000D01*
G01X371500Y-82667D02*
X377500D01*
G01X380500Y-80000D02*
Y-72000D01*
X382900D01*
X383700Y-72400D01*
X384300Y-73333D01*
X384500Y-74400D01*
X384300Y-75467D01*
X383800Y-76267D01*
X382900Y-76667D01*
X380500D01*
G01X388300Y-80000D02*
Y-72000D01*
X390300D01*
X391100Y-72400D01*
X391700Y-72933D01*
X392200Y-73733D01*
X392600Y-74667D01*
X392700Y-76000D01*
X392600Y-77333D01*
X392200Y-78267D01*
X391700Y-79067D01*
X391100Y-79600D01*
X390300Y-80000D01*
X388300D01*
G01X399300Y-75733D02*
X399700Y-75333D01*
X400000Y-74667D01*
X400200Y-73733D01*
X400000Y-72933D01*
X399600Y-72400D01*
X398900Y-72000D01*
X396200D01*
Y-80000D01*
X399500D01*
X400200Y-79467D01*
X400600Y-78667D01*
X400800Y-77733D01*
X400600Y-76800D01*
X400000Y-76000D01*
X399300Y-75733D01*
X396200D01*
G01X403500Y-82667D02*
X409500D01*
G01X412300Y-80000D02*
Y-72000D01*
X414300D01*
X415100Y-72400D01*
X415700Y-72933D01*
X416200Y-73733D01*
X416600Y-74667D01*
X416700Y-76000D01*
X416600Y-77333D01*
X416200Y-78267D01*
X415700Y-79067D01*
X415100Y-79600D01*
X414300Y-80000D01*
X412300D01*
G01X419500Y-82667D02*
X425500D01*
G01X431300Y-75733D02*
X431700Y-75333D01*
X432000Y-74667D01*
X432200Y-73733D01*
X432000Y-72933D01*
X431600Y-72400D01*
X430900Y-72000D01*
X428200D01*
Y-80000D01*
X431500D01*
X432200Y-79467D01*
X432600Y-78667D01*
X432800Y-77733D01*
X432600Y-76800D01*
X432000Y-76000D01*
X431300Y-75733D01*
X428200D01*
G01X436300Y-80000D02*
Y-72000D01*
X438300D01*
X439100Y-72400D01*
X439700Y-72933D01*
X440200Y-73733D01*
X440600Y-74667D01*
X440700Y-76000D01*
X440600Y-77333D01*
X440200Y-78267D01*
X439700Y-79067D01*
X439100Y-79600D01*
X438300Y-80000D01*
X436300D01*
G01X443300Y-130000D02*
Y-122000D01*
X445300D01*
X446100Y-122400D01*
X446700Y-122933D01*
X447200Y-123733D01*
X447600Y-124667D01*
X447700Y-126000D01*
X447600Y-127333D01*
X447200Y-128267D01*
X446700Y-129067D01*
X446100Y-129600D01*
X445300Y-130000D01*
X443300D01*
G01X473000D02*
Y-122000D01*
X471800Y-123600D01*
G01Y-130000D02*
X474200D01*
G01X478800Y-128800D02*
X479400Y-129467D01*
X480100Y-129867D01*
X481000Y-130000D01*
X481900Y-129733D01*
X482600Y-129200D01*
X483100Y-128267D01*
X483200Y-127200D01*
X483000Y-126133D01*
X482500Y-125467D01*
X481800Y-124933D01*
X481100Y-124800D01*
X480400Y-124933D01*
X479500Y-125467D01*
X479800Y-122000D01*
X482500D01*
G54D18*
X23402Y1668874D03*
Y1685410D03*
Y1701945D03*
Y1718480D03*
Y1735016D03*
Y1751551D03*
Y1768087D03*
Y1784622D03*
Y1817693D03*
Y1801158D03*
X45056Y1668874D03*
Y1685410D03*
Y1701945D03*
Y1718480D03*
Y1735016D03*
Y1751551D03*
Y1768087D03*
Y1784622D03*
Y1801158D03*
G54D19*
Y1817693D03*
M02*
